# T6G (Grand Teton) — schematic netlist excerpt (pin names and nets, part order shuffled) for the footprints in the layout excerpt that follows; sources: Cadence DE-HDL packaged netlist, KiCad conversion of 04192023_DAF0TMB3IC0_F0TG_MB_C_brd_V02_OCP.brd

R3454  Q_RES  1K 1% CHIP  pkg 0402LF  page 128 : A = GPU_FPGA_BOOT_EN_BUF_R ; B = GND
PC1648  Q_CAP  0.1UF 25V 10% X6S  pkg C0402  page 189 : A = P12V_AUX ; B = GND

(kicad_pcb
	(version 20260206)
	(generator "pcbnew")
	(generator_version "10.0")
	(general
		(thickness 1.6)
		(legacy_teardrops no)
	)
	(paper "A4")
	(title_block
		(title "04192023_DAF0TMB3IC0_F0TG_MB_C_brd_V02_OCP.brd")
		(comment 1 "Grand Teton / footprints 2990-2991 of 8354")
	)
	(layers
		(0 "F.Cu" signal "TOP")
		(4 "In1.Cu" signal "GND")
		(6 "In2.Cu" signal "IN1")
		(8 "In3.Cu" signal "GND1")
		(10 "In4.Cu" signal "IN2")
		(12 "In5.Cu" signal "GND2")
		(14 "In6.Cu" signal "IN3")
		(16 "In7.Cu" signal "GND3")
		(18 "In8.Cu" signal "VCC")
		(20 "In9.Cu" signal "VCC1")
		(22 "In10.Cu" signal "GND4")
		(24 "In11.Cu" signal "IN4")
		(26 "In12.Cu" signal "GND5")
		(28 "In13.Cu" signal "IN5")
		(30 "In14.Cu" signal "GND6")
		(32 "In15.Cu" signal "IN6")
		(34 "In16.Cu" signal "GND7")
		(2 "B.Cu" signal "BOTTOM")
		(9 "F.Adhes" user "F.Adhesive")
		(11 "B.Adhes" user "B.Adhesive")
		(13 "F.Paste" user "Package Geometry/Pastemask Top")
		(15 "B.Paste" user "Package Geometry/Pastemask Bottom")
		(5 "F.SilkS" user "Ref Des/Silkscreen Top")
		(7 "B.SilkS" user "Ref Des/Silkscreen Bottom")
		(1 "F.Mask" user "Board Geometry/Soldermask Top")
		(3 "B.Mask" user "Board Geometry/Soldermask Bottom")
		(17 "Dwgs.User" user "User.Drawings")
		(19 "Cmts.User" user "User.Comments")
		(21 "Eco1.User" user "User.Eco1")
		(23 "Eco2.User" user "User.Eco2")
		(25 "Edge.Cuts" user "Board Geometry/Outline")
		(27 "Margin" user)
		(31 "F.CrtYd" user "Package Geometry/Place Bound Top")
		(29 "B.CrtYd" user "Package Geometry/Place Bound Bottom")
		(35 "F.Fab" user "Ref Des/Assembly Top")
		(33 "B.Fab" user "Ref Des/Assembly Bottom")
	)
	(footprint ""
		(layer "F.Cu")
		(at 120.396 -425.704 180)
		(property "Reference" "R3454"
			(at 0 0 180)
			(layer "F.SilkS")
			(hide yes)
			(effects
				(font
					(size 1.27 1.27)
				)
			)
		)
		(property "Value" ""
			(at 0 0 180)
			(layer "F.Fab")
			(effects
				(font
					(size 1.27 1.27)
				)
			)
		)
		(duplicate_pad_numbers_are_jumpers no)
		(fp_line
			(start 0.7874 0.4064)
			(end -0.7874 0.4064)
			(stroke
				(width 0.1524)
				(type default)
			)
			(layer "F.SilkS")
		)
		(fp_line
			(start 0.7874 -0.4064)
			(end 0.7874 0.4064)
			(stroke
				(width 0.1524)
				(type default)
			)
			(layer "F.SilkS")
		)
		(fp_line
			(start -0.7874 0.4064)
			(end -0.7874 -0.4064)
			(stroke
				(width 0.1524)
				(type default)
			)
			(layer "F.SilkS")
		)
		(fp_line
			(start -0.7874 -0.4064)
			(end 0.7874 -0.4064)
			(stroke
				(width 0.1524)
				(type default)
			)
			(layer "F.SilkS")
		)
		(fp_line
			(start 0.67945 0.3048)
			(end 0.120396 0.3048)
			(stroke
				(width 0.1)
				(type default)
			)
			(layer "F.Fab")
		)
		(fp_line
			(start 0.67945 -0.3048)
			(end 0.67945 0.3048)
			(stroke
				(width 0.1)
				(type default)
			)
			(layer "F.Fab")
		)
		(fp_line
			(start 0.12065 -0.2794)
			(end 0.12065 -0.3048)
			(stroke
				(width 0.1)
				(type default)
			)
			(layer "F.Fab")
		)
		(fp_line
			(start 0.12065 -0.3048)
			(end 0.67945 -0.3048)
			(stroke
				(width 0.1)
				(type default)
			)
			(layer "F.Fab")
		)
		(fp_line
			(start 0.120396 0.3048)
			(end 0.120396 0.2794)
			(stroke
				(width 0.1)
				(type default)
			)
			(layer "F.Fab")
		)
		(fp_line
			(start 0.120396 0.2794)
			(end -0.12065 0.2794)
			(stroke
				(width 0.1)
				(type default)
			)
			(layer "F.Fab")
		)
		(fp_line
			(start -0.12065 0.3048)
			(end -0.67945 0.3048)
			(stroke
				(width 0.1)
				(type default)
			)
			(layer "F.Fab")
		)
		(fp_line
			(start -0.12065 0.2794)
			(end -0.12065 0.3048)
			(stroke
				(width 0.1)
				(type default)
			)
			(layer "F.Fab")
		)
		(fp_line
			(start -0.12065 -0.2794)
			(end 0.12065 -0.2794)
			(stroke
				(width 0.1)
				(type default)
			)
			(layer "F.Fab")
		)
		(fp_line
			(start -0.12065 -0.305054)
			(end -0.12065 -0.2794)
			(stroke
				(width 0.1)
				(type default)
			)
			(layer "F.Fab")
		)
		(fp_line
			(start -0.67945 0.3048)
			(end -0.67945 -0.305054)
			(stroke
				(width 0.1)
				(type default)
			)
			(layer "F.Fab")
		)
		(fp_line
			(start -0.67945 -0.305054)
			(end -0.12065 -0.305054)
			(stroke
				(width 0.1)
				(type default)
			)
			(layer "F.Fab")
		)
		(pad "1" smd circle
			(at -0.40005 0 180)
			(size 0 0)
			(layers "F.Cu" "F.Mask" "F.Paste")
			(net "GPU_FPGA_BOOT_EN_BUF_R")
		)
		(pad "2" smd circle
			(at 0.40005 0 180)
			(size 0 0)
			(layers "F.Cu" "F.Mask" "F.Paste")
			(net "GND")
		)
	)
	(footprint ""
		(layer "F.Cu")
		(at 410.796486 -134.807706)
		(property "Reference" "PC1648"
			(at 0 0 0)
			(layer "F.SilkS")
			(hide yes)
			(effects
				(font
					(size 1.27 1.27)
				)
			)
		)
		(property "Value" ""
			(at 0 0 0)
			(layer "F.Fab")
			(effects
				(font
					(size 1.27 1.27)
				)
			)
		)
		(duplicate_pad_numbers_are_jumpers no)
		(fp_line
			(start -0.7874 -0.4064)
			(end 0.7874 -0.4064)
			(stroke
				(width 0.1524)
				(type default)
			)
			(layer "F.SilkS")
		)
		(fp_line
			(start -0.7874 0.4064)
			(end -0.7874 -0.4064)
			(stroke
				(width 0.1524)
				(type default)
			)
			(layer "F.SilkS")
		)
		(fp_line
			(start 0.7874 -0.4064)
			(end 0.7874 0.4064)
			(stroke
				(width 0.1524)
				(type default)
			)
			(layer "F.SilkS")
		)
		(fp_line
			(start 0.7874 0.4064)
			(end -0.7874 0.4064)
			(stroke
				(width 0.1524)
				(type default)
			)
			(layer "F.SilkS")
		)
		(fp_line
			(start -0.67945 -0.305054)
			(end -0.12065 -0.305054)
			(stroke
				(width 0.1)
				(type default)
			)
			(layer "F.Fab")
		)
		(fp_line
			(start -0.67945 0.3048)
			(end -0.67945 -0.305054)
			(stroke
				(width 0.1)
				(type default)
			)
			(layer "F.Fab")
		)
		(fp_line
			(start -0.12065 -0.305054)
			(end -0.12065 -0.2794)
			(stroke
				(width 0.1)
				(type default)
			)
			(layer "F.Fab")
		)
		(fp_line
			(start -0.12065 -0.2794)
			(end 0.12065 -0.2794)
			(stroke
				(width 0.1)
				(type default)
			)
			(layer "F.Fab")
		)
		(fp_line
			(start -0.12065 0.2794)
			(end -0.12065 0.3048)
			(stroke
				(width 0.1)
				(type default)
			)
			(layer "F.Fab")
		)
		(fp_line
			(start -0.12065 0.3048)
			(end -0.67945 0.3048)
			(stroke
				(width 0.1)
				(type default)
			)
			(layer "F.Fab")
		)
		(fp_line
			(start 0.120396 0.2794)
			(end -0.12065 0.2794)
			(stroke
				(width 0.1)
				(type default)
			)
			(layer "F.Fab")
		)
		(fp_line
			(start 0.120396 0.3048)
			(end 0.120396 0.2794)
			(stroke
				(width 0.1)
				(type default)
			)
			(layer "F.Fab")
		)
		(fp_line
			(start 0.12065 -0.3048)
			(end 0.67945 -0.3048)
			(stroke
				(width 0.1)
				(type default)
			)
			(layer "F.Fab")
		)
		(fp_line
			(start 0.12065 -0.2794)
			(end 0.12065 -0.3048)
			(stroke
				(width 0.1)
				(type default)
			)
			(layer "F.Fab")
		)
		(fp_line
			(start 0.67945 -0.3048)
			(end 0.67945 0.3048)
			(stroke
				(width 0.1)
				(type default)
			)
			(layer "F.Fab")
		)
		(fp_line
			(start 0.67945 0.3048)
			(end 0.120396 0.3048)
			(stroke
				(width 0.1)
				(type default)
			)
			(layer "F.Fab")
		)
		(pad "1" smd circle
			(at -0.40005 0)
			(size 0 0)
			(layers "F.Cu" "F.Mask" "F.Paste")
			(net "P12V_AUX")
		)
		(pad "2" smd circle
			(at 0.40005 0)
			(size 0 0)
			(layers "F.Cu" "F.Mask" "F.Paste")
			(net "GND")
		)
	)
)
